# TIMECARD (Time Appliance Project (Time Card)) — schematic netlist excerpt (pin names and nets, part order shuffled) for the footprints in the layout excerpt that follows; sources: Cadence DE-HDL packaged netlist, KiCad conversion of R4006-B0001-02_R01.brd

C8  CAPACITOR  0.01UF 25V 10%  pkg SMC_0201R  page 27 : \1\ = XP12R0V_A_OV ; \2\ = SG
TP182  TP_PIONT  pkg TP010CT020B030_PTH  page 25 : \1\ = IO_L21N_16

(kicad_pcb
	(version 20260206)
	(generator "pcbnew")
	(generator_version "10.0")
	(general
		(thickness 1.6)
		(legacy_teardrops no)
	)
	(paper "A4")
	(title_block
		(title "timecard-production-celestica-r4006 — R4006-B0001-02_R01.brd")
		(comment 1 "Time Appliance Project (Time Card) / footprints 209-210 of 1113")
	)
	(layers
		(0 "F.Cu" signal "TOP")
		(4 "In1.Cu" signal "L02_GND1")
		(6 "In2.Cu" signal "L03_SIG1")
		(8 "In3.Cu" signal "L04_GND2")
		(10 "In4.Cu" signal "L05_VCC1")
		(12 "In5.Cu" signal "L06_VCC2")
		(14 "In6.Cu" signal "L07_GND3")
		(16 "In7.Cu" signal "L08_SIG2")
		(18 "In8.Cu" signal "L09_GND4")
		(2 "B.Cu" signal "BOTTOM")
		(9 "F.Adhes" user "F.Adhesive")
		(11 "B.Adhes" user "B.Adhesive")
		(13 "F.Paste" user "Package Geometry/Pastemask Top")
		(15 "B.Paste" user "Package Geometry/Pastemask Bottom")
		(5 "F.SilkS" user "Ref Des/Silkscreen Top")
		(7 "B.SilkS" user "Ref Des/Silkscreen Bottom")
		(1 "F.Mask" user "Board Geometry/Soldermask Top")
		(3 "B.Mask" user "Board Geometry/Soldermask Bottom")
		(17 "Dwgs.User" user "User.Drawings")
		(19 "Cmts.User" user "User.Comments")
		(21 "Eco1.User" user "User.Eco1")
		(23 "Eco2.User" user "User.Eco2")
		(25 "Edge.Cuts" user "Board Geometry/Outline")
		(27 "Margin" user)
		(31 "F.CrtYd" user "Package Geometry/Place Bound Top")
		(29 "B.CrtYd" user "Package Geometry/Place Bound Bottom")
		(35 "F.Fab" user "Ref Des/Assembly Top")
		(33 "B.Fab" user "Ref Des/Assembly Bottom")
	)
	(footprint ""
		(layer "F.Cu")
		(at 96.52 -53.34)
		(property "Reference" "TP182"
			(at 0 0 0)
			(layer "F.SilkS")
			(hide yes)
			(effects
				(font
					(size 1.27 1.27)
				)
			)
		)
		(property "Value" ""
			(at 0 0 0)
			(layer "F.Fab")
			(effects
				(font
					(size 1.27 1.27)
				)
			)
		)
		(property "Device Type" "TP_PIONT-TP010CT020B030_PTH-TPA"
			(at -1.341882 0.996696 0)
			(unlocked yes)
			(layer "F.Fab")
			(hide yes)
			(effects
				(font
					(size 0.7874 0.5842)
					(thickness 0.1524)
				)
				(justify left)
			)
		)
		(duplicate_pad_numbers_are_jumpers no)
		(fp_poly
			(pts
				(arc
					(start 0.889 0)
					(mid -0.889 0)
					(end 0.889 0)
				)
			)
			(stroke
				(width 0)
				(type default)
			)
			(fill no)
			(layer "B.CrtYd")
		)
		(fp_poly
			(pts
				(arc
					(start 0.889 0)
					(mid -0.889 0)
					(end 0.889 0)
				)
			)
			(stroke
				(width 0)
				(type default)
			)
			(fill no)
			(layer "F.CrtYd")
		)
		(pad "1" thru_hole circle
			(at 0 0)
			(size 0.508 0.508)
			(drill 0.254)
			(layers "*.Cu" "*.Mask")
			(remove_unused_layers no)
			(net "IO_L21N_16")
			(clearance 0.1016)
			(padstack
				(mode front_inner_back)
				(layer "Inner"
					(shape circle)
					(size 0.508 0.508)
					(clearance 0.1016)
				)
				(layer "B.Cu"
					(shape circle)
					(size 0.762 0.762)
					(clearance -0.0254)
				)
			)
		)
	)
	(footprint ""
		(layer "F.Cu")
		(at 139.5984 -99.3648 180)
		(property "Reference" "C8"
			(at 1.5494 -0.09017 0)
			(unlocked yes)
			(layer "F.SilkS")
			(effects
				(font
					(size 0.7874 0.5842)
					(thickness 0.1524)
				)
			)
		)
		(property "Value" "VAL*"
			(at 0.193548 2.13614 180)
			(unlocked yes)
			(layer "F.Fab")
			(hide yes)
			(effects
				(font
					(size 0.7874 0.5842)
					(thickness 0.1524)
				)
			)
		)
		(property "Tolerance" "TOL*"
			(at 0.216154 3.1496 180)
			(unlocked yes)
			(layer "Cmts.User")
			(hide yes)
			(effects
				(font
					(size 0.7874 0.5842)
					(thickness 0.1524)
				)
			)
		)
		(property "Device Type" "CAPACITOR-G104-0B103-EK,0.01UFA"
			(at 0.184404 1.180592 180)
			(unlocked yes)
			(layer "F.Fab")
			(hide yes)
			(effects
				(font
					(size 0.7874 0.5842)
					(thickness 0.1524)
				)
			)
		)
		(property "User Part Number" "PARTNUM*"
			(at 0.216154 4.185666 180)
			(unlocked yes)
			(layer "Cmts.User")
			(hide yes)
			(effects
				(font
					(size 0.7874 0.5842)
					(thickness 0.1524)
				)
			)
		)
		(duplicate_pad_numbers_are_jumpers no)
		(fp_line
			(start 0.671322 0.4445)
			(end -0.671322 0.4445)
			(stroke
				(width 0.1)
				(type default)
			)
			(layer "F.SilkS")
		)
		(fp_line
			(start 0.671322 -0.4445)
			(end 0.671322 0.4445)
			(stroke
				(width 0.1)
				(type default)
			)
			(layer "F.SilkS")
		)
		(fp_line
			(start -0.671322 0.4445)
			(end -0.671322 -0.4445)
			(stroke
				(width 0.1)
				(type default)
			)
			(layer "F.SilkS")
		)
		(fp_line
			(start -0.671322 -0.4445)
			(end 0.671322 -0.4445)
			(stroke
				(width 0.1)
				(type default)
			)
			(layer "F.SilkS")
		)
		(fp_rect
			(start -0.671322 0.4445)
			(end 0.671322 -0.4445)
			(stroke
				(width 0)
				(type default)
			)
			(fill no)
			(layer "F.CrtYd")
		)
		(fp_line
			(start 0.31496 0.1651)
			(end 0.31496 -0.1651)
			(stroke
				(width 0.1)
				(type default)
			)
			(layer "F.Fab")
		)
		(fp_line
			(start 0.31496 -0.1651)
			(end -0.31496 -0.1651)
			(stroke
				(width 0.1)
				(type default)
			)
			(layer "F.Fab")
		)
		(fp_line
			(start -0.31496 0.1651)
			(end 0.31496 0.1651)
			(stroke
				(width 0.1)
				(type default)
			)
			(layer "F.Fab")
		)
		(fp_line
			(start -0.31496 -0.1651)
			(end -0.31496 0.1651)
			(stroke
				(width 0.1)
				(type default)
			)
			(layer "F.Fab")
		)
		(pad "1" smd rect
			(at -0.264922 0 180)
			(size 0.3048 0.381)
			(layers "F.Cu" "F.Mask" "F.Paste")
			(net "XP12R0V_A_OV")
		)
		(pad "2" smd rect
			(at 0.264922 0 180)
			(size 0.3048 0.381)
			(layers "F.Cu" "F.Mask" "F.Paste")
			(net "SG")
		)
		(zone
			(layer "F.Cu")
			(hatch none 0.5)
			(connect_pads
				(clearance 0)
			)
			(min_thickness 0.25)
			(keepout
				(tracks allowed)
				(vias not_allowed)
				(pads allowed)
				(copperpour not_allowed)
				(footprints allowed)
			)
			(placement
				(enabled no)
				(sheetname "")
			)
			(fill
				(thermal_gap 0.5)
				(thermal_bridge_width 0.5)
				(island_removal_mode 0)
			)
			(polygon
				(pts
					(xy 139.710922 -99.5553) (xy 139.485878 -99.5553) (xy 139.485878 -99.1743) (xy 139.710922 -99.1743)
				)
			)
		)
	)
)
